# S9S_MB_2U (Grand Teton) — schematic netlist excerpt (pin names and nets, part order shuffled) for the footprints in the layout excerpt that follows; sources: Cadence DE-HDL packaged netlist, KiCad conversion of 03242023_DA0F0TMBIJ0_F0T_Motherboard_J_brd_V01_OCP.brd

J7  SCONN288_ADR50017P130CC  SCONN288_ADR50017-P130CC IO  pkg DDR288S_1-1VXB  page 88
  VIN_BULK0  = P12V_S3_AUX_CPU0_NVDIMM
  RFU0  = TP_CHD_CPU0_DIMM1_FRU_0
  VIN_MGMT  = P3V3_AUX
  HSCL  = I3C_SPD_DDRABCD_CPU0_LVC1_SCL_6
  HSDA  = I3C_SPD_DDRABCD_CPU0_LVC1_SDA
  VSS0  = GND
  DQ0_A  = M_D_CPU0_SA_DQ<0>
  VSS1  = GND
  DQ1_A  = M_D_CPU0_SA_DQ<1>
  VSS2  = GND
  DQS0_A_T  = M_D_CPU0_SA_DQS_DP<0>
  DQS0_A_C  = M_D_CPU0_SA_DQS_DN<0>
  VSS3  = GND
  DQ4_A  = M_D_CPU0_SA_DQ<4>
  VSS4  = GND
  DQ5_A  = M_D_CPU0_SA_DQ<5>
  VSS5  = GND
  DQ8_A  = M_D_CPU0_SA_DQ<8>
  VSS6  = GND
  DQ9_A  = M_D_CPU0_SA_DQ<9>
  VSS7  = GND
  DQS1_A_T  = M_D_CPU0_SA_DQS_DP<1>
  DQS1_A_C  = M_D_CPU0_SA_DQS_DN<1>
  VSS8  = GND
  DQ12_A  = M_D_CPU0_SA_DQ<12>
  VSS9  = GND
  DQ13_A  = M_D_CPU0_SA_DQ<13>
  VSS10  = GND
  DQ16_A  = M_D_CPU0_SA_DQ<16>
  VSS11  = GND
  DQ17_A  = M_D_CPU0_SA_DQ<17>
  VSS12  = GND
  DQS2_A_T  = M_D_CPU0_SA_DQS_DP<2>
  DQS2_A_C  = M_D_CPU0_SA_DQS_DN<2>
  VSS13  = GND
  DQ20_A  = M_D_CPU0_SA_DQ<20>
  VSS14  = GND
  DQ21_A  = M_D_CPU0_SA_DQ<21>
  VSS15  = GND
  DQ24_A  = M_D_CPU0_SA_DQ<24>
  VSS16  = GND
  DQ25_A  = M_D_CPU0_SA_DQ<25>
  VSS17  = GND
  DQS3_A_T  = M_D_CPU0_SA_DQS_DP<3>
  DQS3_A_C  = M_D_CPU0_SA_DQS_DN<3>
  VSS18  = GND
  DQ28_A  = M_D_CPU0_SA_DQ<28>
  VSS19  = GND
  DQ29_A  = M_D_CPU0_SA_DQ<29>
  VSS20  = GND
  CB0_A  = M_D_CPU0_SA_CB<0>
  VSS21  = GND
  CB1_A  = M_D_CPU0_SA_CB<1>
  VSS22  = GND
  DQS4_A_T  = M_D_CPU0_SA_DQS_DP<4>
  DQS4_A_C  = M_D_CPU0_SA_DQS_DN<4>
  VSS23  = GND
  CB4_A  = M_D_CPU0_SA_CB<4>
  VSS24  = GND
  CB5_A  = M_D_CPU0_SA_CB<5>
  VSS25  = GND
  ALERT_N  = M_D_CPU0_ALERT_N
  VSS26  = GND
  CS0_A_N  = M_D_CPU0_SA_CS_N<0>
  VSS27  = GND
  CA0_A  = M_D_CPU0_SA_CA<0>
  VSS28  = GND
  CA2_A  = M_D_CPU0_SA_CA<2>
  VSS29  = GND
  CA4_A  = M_D_CPU0_SA_CA<4>
  VSS30  = GND
  CA6_A  = M_D_CPU0_SA_CA<6>
  VSS31  = GND
  PAR_A  = M_D_CPU0_SA_PAR
  VSS32  = GND
  CA0_B  = M_D_CPU0_SB_CA<0>
  VSS33  = GND
  CA2_B  = M_D_CPU0_SB_CA<2>
  VSS34  = GND
  CA4_B  = M_D_CPU0_SB_CA<4>
  VSS35  = GND
  CA6_B  = M_D_CPU0_SB_CA<6>
  VSS36  = GND
  CS0_B_N  = M_D_CPU0_SB_CS_N<0>
  VSS37  = GND
  \lbd||rsp_a_n\  = M_D_CPU0_SA_RSP<0>
  \lbs||rsp_b_n\  = M_D_CPU0_SB_RSP<0>
  VSS38  = GND
  CB4_B  = M_D_CPU0_SB_CB<4>
  VSS39  = GND
  CB5_B  = M_D_CPU0_SB_CB<5>
  VSS40  = GND
  \dqs9_b_t||tdqs9_b_t||dbi4_b_n\  = M_D_CPU0_SB_DQS_DP<9>
  \dqs9_b_c||tdqs9_b_c\  = M_D_CPU0_SB_DQS_DN<9>
  VSS41  = GND
  CB0_B  = M_D_CPU0_SB_CB<0>
  VSS42  = GND
  CB1_B  = M_D_CPU0_SB_CB<1>
  VSS43  = GND
  DQ0_B  = M_D_CPU0_SB_DQ<0>
  VSS44  = GND
  DQ1_B  = M_D_CPU0_SB_DQ<1>
  VSS45  = GND
  DQS0_B_T  = M_D_CPU0_SB_DQS_DP<0>
  DQS0_B_C  = M_D_CPU0_SB_DQS_DN<0>
  VSS46  = GND
  DQ4_B  = M_D_CPU0_SB_DQ<4>
  VSS47  = GND
  DQ5_B  = M_D_CPU0_SB_DQ<5>
  VSS48  = GND
  DQ8_B  = M_D_CPU0_SB_DQ<8>
  VSS49  = GND
  DQ9_B  = M_D_CPU0_SB_DQ<9>
  VSS50  = GND
  DQS1_B_T  = M_D_CPU0_SB_DQS_DP<1>
  DQS1_B_C  = M_D_CPU0_SB_DQS_DN<1>
  VSS51  = GND
  DQ12_B  = M_D_CPU0_SB_DQ<12>
  VSS52  = GND
  DQ13_B  = M_D_CPU0_SB_DQ<13>
  VSS53  = GND
  DQ16_B  = M_D_CPU0_SB_DQ<16>
  VSS54  = GND
  DQ17_B  = M_D_CPU0_SB_DQ<17>
  VSS55  = GND
  DQS2_B_T  = M_D_CPU0_SB_DQS_DP<2>
  DQS2_B_C  = M_D_CPU0_SB_DQS_DN<2>
  VSS56  = GND
  DQ20_B  = M_D_CPU0_SB_DQ<20>
  VSS57  = GND
  DQ21_B  = M_D_CPU0_SB_DQ<21>
  VSS58  = GND
  DQ24_B  = M_D_CPU0_SB_DQ<24>
  VSS59  = GND
  DQ25_B  = M_D_CPU0_SB_DQ<25>
  VSS60  = GND
  DQS3_B_T  = M_D_CPU0_SB_DQS_DP<3>
  DQS3_B_C  = M_D_CPU0_SB_DQS_DN<3>
  VSS61  = GND
  DQ28_B  = M_D_CPU0_SB_DQ<28>
  VSS62  = GND
  DQ29_B  = M_D_CPU0_SB_DQ<29>
  VSS63  = GND
  RFU1  = TP_CHD_CPU0_DIMM1_FRU_1
  VIN_BULK1  = P12V_S3_AUX_CPU0_NVDIMM
  VIN_BULK2  = P12V_S3_AUX_CPU0_NVDIMM
  \pwr_good||fail_n\  = PWRGD_CHD_CPU0_DIMM1
  HSA  = PD_CHD_CPU0_DIMM1_SAA
  RFU2  = TP_CHD_CPU0_DIMM1_FRU_2
  RFU3  = TP_CHD_CPU0_DIMM1_FRU_3
  VSS64  = GND
  DQ2_A  = M_D_CPU0_SA_DQ<2>
  VSS65  = GND
  DQ3_A  = M_D_CPU0_SA_DQ<3>
  VSS66  = GND
  \dqs5_a_c||tdqs5_a_c||dqs5_a_t||tdqs5_a_t\  = M_D_CPU0_SA_DQS_DN<5>
  \dqs5_a_t||tdqs5_a_t\  = M_D_CPU0_SA_DQS_DP<5>
  VSS67  = GND
  DQ6_A  = M_D_CPU0_SA_DQ<6>
  VSS68  = GND
  DQ7_A  = M_D_CPU0_SA_DQ<7>
  VSS69  = GND
  DQ10_A  = M_D_CPU0_SA_DQ<10>
  VSS70  = GND
  DQ11_A  = M_D_CPU0_SA_DQ<11>
  VSS71  = GND
  \dqs6_a_c||tdqs6_a_c||dqs6_a_t||tdqs6_a_t\  = M_D_CPU0_SA_DQS_DN<6>
  \dqs6_a_t||tdqs6_a_t\  = M_D_CPU0_SA_DQS_DP<6>
  VSS72  = GND
  DQ14_A  = M_D_CPU0_SA_DQ<14>
  VSS73  = GND
  DQ15_A  = M_D_CPU0_SA_DQ<15>
  VSS74  = GND
  DQ18_A  = M_D_CPU0_SA_DQ<18>
  VSS75  = GND
  DQ19_A  = M_D_CPU0_SA_DQ<19>
  VSS76  = GND
  \dqs7_a_c||tdqs7_a_c\  = M_D_CPU0_SA_DQS_DN<7>
  \dqs7_a_t||tdqs7_a_t\  = M_D_CPU0_SA_DQS_DP<7>
  VSS77  = GND
  DQ22_A  = M_D_CPU0_SA_DQ<22>
  VSS78  = GND
  DQ23_A  = M_D_CPU0_SA_DQ<23>
  VSS79  = GND
  DQ26_A  = M_D_CPU0_SA_DQ<26>
  VSS80  = GND
  DQ27_A  = M_D_CPU0_SA_DQ<27>
  VSS81  = GND
  \dqs8_a_c||tdqs8_a_c\  = M_D_CPU0_SA_DQS_DN<8>
  \dqs8_a_t||tdqs8_a_t\  = M_D_CPU0_SA_DQS_DP<8>
  VSS82  = GND
  DQ30_A  = M_D_CPU0_SA_DQ<30>
  VSS83  = GND
  DQ31_A  = M_D_CPU0_SA_DQ<31>
  VSS84  = GND
  CB2_A  = M_D_CPU0_SA_CB<2>
  VSS85  = GND
  CB3_A  = M_D_CPU0_SA_CB<3>
  VSS86  = GND
  \dqs9_a_c||tdqs9_a_c\  = M_D_CPU0_SA_DQS_DN<9>
  \dqs9_a_t||tdqs9_a_t\  = M_D_CPU0_SA_DQS_DP<9>
  VSS87  = GND
  CB6_A  = M_D_CPU0_SA_CB<6>
  VSS88  = GND
  CB7_A  = M_D_CPU0_SA_CB<7>
  VSS89  = GND
  RESET_N  = RST_M_CD_CPU0_FPGA_N
  VSS90  = GND
  CS1_A_N  = M_D_CPU0_SA_CS_N<1>
  VSS91  = GND
  CA1_A  = M_D_CPU0_SA_CA<1>
  VSS92  = GND
  CA3_A  = M_D_CPU0_SA_CA<3>
  VSS93  = GND
  CA5_A  = M_D_CPU0_SA_CA<5>
  VSS94  = GND
  CK_T  = M_D_CPU0_CLK_DP<0>
  CK_C  = M_D_CPU0_CLK_DN<0>
  VSS95  = GND
  RFU4  = TP_CHD_CPU0_DIMM1_FRU_4
  CA1_B  = M_D_CPU0_SB_CA<1>
  VSS96  = GND
  CA3_B  = M_D_CPU0_SB_CA<3>
  VSS97  = GND
  CA5_B  = M_D_CPU0_SB_CA<5>
  VSS98  = GND
  PAR_B  = M_D_CPU0_SB_PAR
  VSS99  = GND
  CS1_B_N  = M_D_CPU0_SB_CS_N<1>
  VSS100  = GND
  RFU5  = TP_CHD_CPU0_DIMM1_FRU_5
  RFU6  = TP_CHD_CPU0_DIMM1_FRU_6
  VSS101  = GND
  CB6_B  = M_D_CPU0_SB_CB<6>
  VSS102  = GND
  CB7_B  = M_D_CPU0_SB_CB<7>
  VSS103  = GND
  DQS4_B_C  = M_D_CPU0_SB_DQS_DN<4>
  DQS4_B_T  = M_D_CPU0_SB_DQS_DP<4>
  VSS104  = GND
  CB2_B  = M_D_CPU0_SB_CB<2>
  VSS105  = GND
  CB3_B  = M_D_CPU0_SB_CB<3>
  VSS106  = GND
  DQ2_B  = M_D_CPU0_SB_DQ<2>
  VSS107  = GND
  DQ3_B  = M_D_CPU0_SB_DQ<3>
  VSS108  = GND
  \dqs5_b_c||tdqs5_b_c\  = M_D_CPU0_SB_DQS_DN<5>
  \dqs5_b_t||tdqs5_b_t\  = M_D_CPU0_SB_DQS_DP<5>
  VSS109  = GND
  DQ6_B  = M_D_CPU0_SB_DQ<6>
  VSS110  = GND
  DQ7_B  = M_D_CPU0_SB_DQ<7>
  VSS111  = GND
  DQ10_B  = M_D_CPU0_SB_DQ<10>
  VSS112  = GND
  DQ11_B  = M_D_CPU0_SB_DQ<11>
  VSS113  = GND
  \dqs6_b_c||tdqs6_b_c\  = M_D_CPU0_SB_DQS_DN<6>
  \dqs6_b_t||tdqs6_b_t\  = M_D_CPU0_SB_DQS_DP<6>
  VSS114  = GND
  DQ14_B  = M_D_CPU0_SB_DQ<14>
  VSS115  = GND
  DQ15_B  = M_D_CPU0_SB_DQ<15>
  VSS116  = GND
  DQ18_B  = M_D_CPU0_SB_DQ<18>
  VSS117  = GND
  DQ19_B  = M_D_CPU0_SB_DQ<19>
  VSS118  = GND
  \dqs7_b_c||tdqs7_b_c\  = M_D_CPU0_SB_DQS_DN<7>
  \dqs7_b_t||tdqs7_b_t\  = M_D_CPU0_SB_DQS_DP<7>
  VSS119  = GND
  DQ22_B  = M_D_CPU0_SB_DQ<22>
  VSS120  = GND
  DQ23_B  = M_D_CPU0_SB_DQ<23>
  VSS121  = GND
  DQ26_B  = M_D_CPU0_SB_DQ<26>
  VSS122  = GND
  DQ27_B  = M_D_CPU0_SB_DQ<27>
  VSS123  = GND
  \dqs8_b_c||tdqs8_b_c\  = M_D_CPU0_SB_DQS_DN<8>
  \dqs8_b_t||tdqs8_b_t\  = M_D_CPU0_SB_DQS_DP<8>
  VSS124  = GND
  DQ30_B  = M_D_CPU0_SB_DQ<30>
  VSS125  = GND
  DQ31_B  = M_D_CPU0_SB_DQ<31>
  VSS126  = GND
  G1  = GND
  G2  = GND
  G3  = GND

(kicad_pcb
	(version 20260206)
	(generator "pcbnew")
	(generator_version "10.0")
	(general
		(thickness 1.6)
		(legacy_teardrops no)
	)
	(paper "A4")
	(title_block
		(title "03242023_DA0F0TMBIJ0_F0T_Motherboard_J_brd_V01_OCP.brd")
		(comment 1 "Grand Teton / footprint 37 of 6105 (J7), pads 183-228 of 291")
	)
	(layers
		(0 "F.Cu" signal "TOP")
		(4 "In1.Cu" signal "GND")
		(6 "In2.Cu" signal "IN1")
		(8 "In3.Cu" signal "GND1")
		(10 "In4.Cu" signal "IN2")
		(12 "In5.Cu" signal "GND2")
		(14 "In6.Cu" signal "IN3")
		(16 "In7.Cu" signal "GND3")
		(18 "In8.Cu" signal "VCC")
		(20 "In9.Cu" signal "VCC1")
		(22 "In10.Cu" signal "GND4")
		(24 "In11.Cu" signal "IN4")
		(26 "In12.Cu" signal "GND5")
		(28 "In13.Cu" signal "IN5")
		(30 "In14.Cu" signal "GND6")
		(32 "In15.Cu" signal "IN6")
		(34 "In16.Cu" signal "GND7")
		(2 "B.Cu" signal "BOTTOM")
		(9 "F.Adhes" user "F.Adhesive")
		(11 "B.Adhes" user "B.Adhesive")
		(13 "F.Paste" user "Package Geometry/Pastemask Top")
		(15 "B.Paste" user "Package Geometry/Pastemask Bottom")
		(5 "F.SilkS" user "Ref Des/Silkscreen Top")
		(7 "B.SilkS" user "Ref Des/Silkscreen Bottom")
		(1 "F.Mask" user "Board Geometry/Soldermask Top")
		(3 "B.Mask" user "Board Geometry/Soldermask Bottom")
		(17 "Dwgs.User" user "User.Drawings")
		(19 "Cmts.User" user "User.Comments")
		(21 "Eco1.User" user "User.Eco1")
		(23 "Eco2.User" user "User.Eco2")
		(25 "Edge.Cuts" user "Board Geometry/Outline")
		(27 "Margin" user)
		(31 "F.CrtYd" user "Package Geometry/Place Bound Top")
		(29 "B.CrtYd" user "Package Geometry/Place Bound Bottom")
		(35 "F.Fab" user "Ref Des/Assembly Top")
		(33 "B.Fab" user "Ref Des/Assembly Bottom")
	)
	(footprint ""
		(layer "F.Cu")
		(at 258.130548 -258.091686)
		(property "Reference" "J7"
			(at -3.683 -81.702148 0)
			(unlocked yes)
			(layer "F.SilkS")
			(effects
				(font
					(size 0.7874 0.5842)
					(thickness 0.1524)
				)
				(justify left)
			)
		)
		(property "Value" ""
			(at 0 0 0)
			(layer "F.Fab")
			(effects
				(font
					(size 1.27 1.27)
				)
			)
		)
		(duplicate_pad_numbers_are_jumpers no)
		(pad "183" smd rect
			(at 2.050034 -31.025084 270)
			(size 0.519938 1.4986)
			(layers "F.Cu" "F.Mask" "F.Paste")
			(net "M_D_CPU0_SA_DQ<23>")
		)
		(pad "184" smd rect
			(at 2.050034 -30.174946 270)
			(size 0.519938 1.4986)
			(layers "F.Cu" "F.Mask" "F.Paste")
			(net "GND")
		)
		(pad "185" smd rect
			(at 2.050034 -29.325062 270)
			(size 0.519938 1.4986)
			(layers "F.Cu" "F.Mask" "F.Paste")
			(net "M_D_CPU0_SA_DQ<26>")
		)
		(pad "186" smd rect
			(at 2.050034 -28.474924 270)
			(size 0.519938 1.4986)
			(layers "F.Cu" "F.Mask" "F.Paste")
			(net "GND")
		)
		(pad "187" smd rect
			(at 2.050034 -27.62504 270)
			(size 0.519938 1.4986)
			(layers "F.Cu" "F.Mask" "F.Paste")
			(net "M_D_CPU0_SA_DQ<27>")
		)
		(pad "188" smd rect
			(at 2.050034 -26.774902 270)
			(size 0.519938 1.4986)
			(layers "F.Cu" "F.Mask" "F.Paste")
			(net "GND")
		)
		(pad "189" smd rect
			(at 2.050034 -25.925018 270)
			(size 0.519938 1.4986)
			(layers "F.Cu" "F.Mask" "F.Paste")
			(net "M_D_CPU0_SA_DQS_DN<8>")
		)
		(pad "190" smd rect
			(at 2.050034 -25.07488 270)
			(size 0.519938 1.4986)
			(layers "F.Cu" "F.Mask" "F.Paste")
			(net "M_D_CPU0_SA_DQS_DP<8>")
		)
		(pad "191" smd rect
			(at 2.050034 -24.224996 270)
			(size 0.519938 1.4986)
			(layers "F.Cu" "F.Mask" "F.Paste")
			(net "GND")
		)
		(pad "192" smd rect
			(at 2.050034 -23.375112 270)
			(size 0.519938 1.4986)
			(layers "F.Cu" "F.Mask" "F.Paste")
			(net "M_D_CPU0_SA_DQ<30>")
		)
		(pad "193" smd rect
			(at 2.050034 -22.524974 270)
			(size 0.519938 1.4986)
			(layers "F.Cu" "F.Mask" "F.Paste")
			(net "GND")
		)
		(pad "194" smd rect
			(at 2.050034 -21.67509 270)
			(size 0.519938 1.4986)
			(layers "F.Cu" "F.Mask" "F.Paste")
			(net "M_D_CPU0_SA_DQ<31>")
		)
		(pad "195" smd rect
			(at 2.050034 -20.824952 270)
			(size 0.519938 1.4986)
			(layers "F.Cu" "F.Mask" "F.Paste")
			(net "GND")
		)
		(pad "196" smd rect
			(at 2.050034 -19.975068 270)
			(size 0.519938 1.4986)
			(layers "F.Cu" "F.Mask" "F.Paste")
			(net "M_D_CPU0_SA_CB<2>")
		)
		(pad "197" smd rect
			(at 2.050034 -19.12493 270)
			(size 0.519938 1.4986)
			(layers "F.Cu" "F.Mask" "F.Paste")
			(net "GND")
		)
		(pad "198" smd rect
			(at 2.050034 -18.275046 270)
			(size 0.519938 1.4986)
			(layers "F.Cu" "F.Mask" "F.Paste")
			(net "M_D_CPU0_SA_CB<3>")
		)
		(pad "199" smd rect
			(at 2.050034 -17.424908 270)
			(size 0.519938 1.4986)
			(layers "F.Cu" "F.Mask" "F.Paste")
			(net "GND")
		)
		(pad "200" smd rect
			(at 2.050034 -16.575024 270)
			(size 0.519938 1.4986)
			(layers "F.Cu" "F.Mask" "F.Paste")
			(net "M_D_CPU0_SA_DQS_DN<9>")
		)
		(pad "201" smd rect
			(at 2.050034 -15.724886 270)
			(size 0.519938 1.4986)
			(layers "F.Cu" "F.Mask" "F.Paste")
			(net "M_D_CPU0_SA_DQS_DP<9>")
		)
		(pad "202" smd rect
			(at 2.050034 -14.875002 270)
			(size 0.519938 1.4986)
			(layers "F.Cu" "F.Mask" "F.Paste")
			(net "GND")
		)
		(pad "203" smd rect
			(at 2.050034 -14.025118 270)
			(size 0.519938 1.4986)
			(layers "F.Cu" "F.Mask" "F.Paste")
			(net "M_D_CPU0_SA_CB<6>")
		)
		(pad "204" smd rect
			(at 2.050034 -13.17498 270)
			(size 0.519938 1.4986)
			(layers "F.Cu" "F.Mask" "F.Paste")
			(net "GND")
		)
		(pad "205" smd rect
			(at 2.050034 -12.325096 270)
			(size 0.519938 1.4986)
			(layers "F.Cu" "F.Mask" "F.Paste")
			(net "M_D_CPU0_SA_CB<7>")
		)
		(pad "206" smd rect
			(at 2.050034 -11.474958 270)
			(size 0.519938 1.4986)
			(layers "F.Cu" "F.Mask" "F.Paste")
			(net "GND")
		)
		(pad "207" smd rect
			(at 2.050034 -10.625074 270)
			(size 0.519938 1.4986)
			(layers "F.Cu" "F.Mask" "F.Paste")
			(net "RST_M_CD_CPU0_FPGA_N")
		)
		(pad "208" smd rect
			(at 2.050034 -9.774936 270)
			(size 0.519938 1.4986)
			(layers "F.Cu" "F.Mask" "F.Paste")
			(net "GND")
		)
		(pad "209" smd rect
			(at 2.050034 -8.925052 270)
			(size 0.519938 1.4986)
			(layers "F.Cu" "F.Mask" "F.Paste")
			(net "M_D_CPU0_SA_CS_N<1>")
		)
		(pad "210" smd rect
			(at 2.050034 -8.074914 270)
			(size 0.519938 1.4986)
			(layers "F.Cu" "F.Mask" "F.Paste")
			(net "GND")
		)
		(pad "211" smd rect
			(at 2.050034 -7.22503 270)
			(size 0.519938 1.4986)
			(layers "F.Cu" "F.Mask" "F.Paste")
			(net "M_D_CPU0_SA_CA<1>")
		)
		(pad "212" smd rect
			(at 2.050034 -6.374892 270)
			(size 0.519938 1.4986)
			(layers "F.Cu" "F.Mask" "F.Paste")
			(net "GND")
		)
		(pad "213" smd rect
			(at 2.050034 -5.525008 270)
			(size 0.519938 1.4986)
			(layers "F.Cu" "F.Mask" "F.Paste")
			(net "M_D_CPU0_SA_CA<3>")
		)
		(pad "214" smd rect
			(at 2.050034 -4.675124 270)
			(size 0.519938 1.4986)
			(layers "F.Cu" "F.Mask" "F.Paste")
			(net "GND")
		)
		(pad "215" smd rect
			(at 2.050034 -3.824986 270)
			(size 0.519938 1.4986)
			(layers "F.Cu" "F.Mask" "F.Paste")
			(net "M_D_CPU0_SA_CA<5>")
		)
		(pad "216" smd rect
			(at 2.050034 -2.975102 270)
			(size 0.519938 1.4986)
			(layers "F.Cu" "F.Mask" "F.Paste")
			(net "GND")
		)
		(pad "217" smd rect
			(at 2.050034 -2.124964 270)
			(size 0.519938 1.4986)
			(layers "F.Cu" "F.Mask" "F.Paste")
			(net "M_D_CPU0_CLK_DP<0>")
		)
		(pad "218" smd rect
			(at 2.050034 -1.27508 270)
			(size 0.519938 1.4986)
			(layers "F.Cu" "F.Mask" "F.Paste")
			(net "M_D_CPU0_CLK_DN<0>")
		)
		(pad "219" smd rect
			(at 2.050034 -0.424942 270)
			(size 0.519938 1.4986)
			(layers "F.Cu" "F.Mask" "F.Paste")
			(net "GND")
		)
		(pad "220" smd rect
			(at 2.050034 5.525008 270)
			(size 0.519938 1.4986)
			(layers "F.Cu" "F.Mask" "F.Paste")
			(net "TP_CHD_CPU0_DIMM1_FRU_4")
		)
		(pad "221" smd rect
			(at 2.050034 6.374892 270)
			(size 0.519938 1.4986)
			(layers "F.Cu" "F.Mask" "F.Paste")
			(net "M_D_CPU0_SB_CA<1>")
		)
		(pad "222" smd rect
			(at 2.050034 7.22503 270)
			(size 0.519938 1.4986)
			(layers "F.Cu" "F.Mask" "F.Paste")
			(net "GND")
		)
		(pad "223" smd rect
			(at 2.050034 8.074914 270)
			(size 0.519938 1.4986)
			(layers "F.Cu" "F.Mask" "F.Paste")
			(net "M_D_CPU0_SB_CA<3>")
		)
		(pad "224" smd rect
			(at 2.050034 8.925052 270)
			(size 0.519938 1.4986)
			(layers "F.Cu" "F.Mask" "F.Paste")
			(net "GND")
		)
		(pad "225" smd rect
			(at 2.050034 9.774936 270)
			(size 0.519938 1.4986)
			(layers "F.Cu" "F.Mask" "F.Paste")
			(net "M_D_CPU0_SB_CA<5>")
		)
		(pad "226" smd rect
			(at 2.050034 10.625074 270)
			(size 0.519938 1.4986)
			(layers "F.Cu" "F.Mask" "F.Paste")
			(net "GND")
		)
		(pad "227" smd rect
			(at 2.050034 11.474958 270)
			(size 0.519938 1.4986)
			(layers "F.Cu" "F.Mask" "F.Paste")
			(net "M_D_CPU0_SB_PAR")
		)
		(pad "228" smd rect
			(at 2.050034 12.325096 270)
			(size 0.519938 1.4986)
			(layers "F.Cu" "F.Mask" "F.Paste")
			(net "GND")
		)
	)
)
